TITLE: Bill of Materials
DATE: 08/19/2021
DESIGN: scm
TEMPLATE: c:\cadence\spb_17.2\share\cdssetup\template.bom
CALLOUT: 

S.No.,PART_NUMBER,DESCRIPTION,MATERIAL,Qty,MANUFTR,MANUF_PN,Ref Des,QPN,LIFECYCLE,STANDARD
0,AJ026000T04,IC CTRL(624P)AST2600A1-GP(TFBGA),IC,1,APD,AST2600A1-GP,U5,?,?,?
1,AJ10M020T00,IC OTHER(169P)10M02SCU169C8G(UBGA),IC,1,INT,10M02SCU169C8G,U25,?,?,?
2,AKD5FGUT502,IC SDRAM(96P)K4A8G165WC-BCTD(FBGA)QBCON,IC,1,SAM,K4A8G165WC-BCTD,U1,?,?,?
3,AKE30Z0K610,IC(8P)M24128-BWDW6TP(TSSOP),IC,1,SGT,M24128-BWDW6TP,U19,?,?,?
4,AL0000750E3,IC(8P) TMP75AIDGKR (MSOP),IC,1,TIC,TMP75AIDGKR,U4,?,?,?
5,AL000234001,IC OTHER(12P)FT234XD-R(DFN),IC,1,FTI,FT234XD-R,U17,?,?,?
6,AL000257K00,IC OTHER(16P)IDTQS3VH257PAG(TSSOP),IC,2,?,IDTQS3VH257PAG,"U21,U30",?,?,?
7,AL000695001,IC CTRL(13P)NB695GD-Z(QFN-13),IC,2,MPS,NB695GD-Z,"PU41,PU42",?,?,?
8,AL002553002,IC OTHER(6P) TPS2553DBVR-1(SOT23),IC,1,TIC,TPS2553DBVR-1,U10,?,?,?
9,AL002G07006,IC(6P) SN74LVC2G07DCKR(SC70-6),IC,3,?,SN74LVC2G07DCKR,"U6,U24,U47",?,?,?
10,AL006126001,IC OTHER(42P) HD3SS6126RUAR (WQFN),IC,1,TIC,HD3SS6126RUAR,U22,?,?,?
11,AL008626000,IC CTRL(14P)MPQ8626GD-Z(QFN),IC,1,MPS,MPQ8626GD-Z,PU1,?,?,?
12,AL008633007,IC CTRL(21P)MPQ8633AGLE-C807-Z(QFN),IC,1,MPS,MPQ8633AGLE-C807-Z,PU38,?,?,?
13,AL009059000,IC OTHER(10P) RT9059GQW(WDFN),IC,2,RTK,RT9059GQW,"PU39,PU40",?,?,?
14,AL009517K00,IC OTHER (8P) PCA9517ADP(TSSOP8),IC,1,?,?,U37,?,?,?
15,AL022811000,IC OTHER(5P)AP22811AW5-7(SOT25),IC,1,DDS,AP22811AW5-7,U14,?,?,?
16,AL022965000,IC OTHER (8P) TPS22965DSGR(SON),IC,1,TIC,TPS22965DSGR,U15,?,?,?
17,AL054612B00,IC OTHER(48P) BCM54612EB1KMLG(MLP),IC,1,BCM,BCM54612EB1KMLG,U7,?,?,?
18,AL1G0007016,IC OTHER(5P)SN74LVC1G07DCKR(SOT),IC,1,TIC,SN74LVC1G07DCKR,U13,?,?,?
19,AL1G0007016,IC OTHER(5P)SN74LVC1G07DCKR(SOT),EMPTY,1,TIC,SN74LVC1G07DCKR,U44,?,?,?
20,AL1G0007024,IC(5P) SN74LVC1G07DCKR(SOP),IC,1,?,?,U23,?,?,?
21,AL1G0017003,IC(5P) SN74LVC1G17DCKR (SC-70),IC,1,TIC,SN74LVC1G17DCKR,U46,?,?,?
22,AL1G0017K01,IC OTHER(5P) 74LVC1G17GW(TSSOP),IC,1,NXP,74LVC1G17GW,U32,?,?,?
23,AL1G0126007,IC(5P) 74HC1G126GW(SOT353)EP,IC,4,PHI,74HC1G126GW,"U26,U29,U33,U36",?,?,?
24,AL1G3157001,IC OTHER(6P) SN74LVC1G3157DCKR(SC70-6),IC,4,TIC,SN74LVC1G3157DCKR,"U2,U3,U41,U42",?,?,?
25,AL2EUSB3000,IC OTHER(3P) TPD2EUSB30DRTR (SOT),IC,3,TIC,TPD2EUSB30DRTR,"U18,U27,U39",?,?,?
26,AL380833000,IC OTHER(6P) TPS3808G33DBVR(SOT23)HF,IC,1,TIC,TPS3808G33DBVR,U43,?,?,?
27,AL5V0U2X000,IC OTHER (4P) PRTR5V0U2X (SOT143B),IC,1,NXP,PRTR5V0U2X,U38,?,?,?
28,ALVC1G07002,IC(5P) 74LVC1G07GW(SOT353),IC,1,PHI,74LVC1G07GW,U31,?,?,?
29,BA0390400H0,"TRANS SMD MMBT3904-7-F(40V,200MA,8W)",IC,2,DDS,MMBT3904-7-F,"Q1,Q3",?,Comp-Approve,End of Design
30,BAM01230014,TRANS MOSFET BSS123-7-F(100V.170MA),IC,1,DDS,BSS123-7-F,Q7,?,?,?
31,BAM138K0000,"TRANS MOS BSS138K(50V,0.22A,0.35W)",IC,1,?,BSS138K,U12,?,?,?
32,BAM23050027,"TRAN P-MOSFET AP2305GN-20V,1.38W(SOT-23)",EMPTY,1,AVP,AP2305GN,Q4,?,?,?
33,BAM41410005,"TRANS MOS NTGS4141NT1G(30V,7.0A,TSOP6)",IC,1,ONS,NTGS4141NT1G,Q5,?,Comp-Approve,End of Design
34,BAM69680000,"TRANS MOS DMG6968U-7(20V,6.5A,1.3W)SOT23",IC,1,DDS,DMG6968U-7,Q10,?,Comp-Approve,End of Design
35,BAM70020047,"TRANS MOS 2N7002KDW(60V115MA,0.2W)SOT363",IC,2,PJT,2N7002KDW,"Q2,Q12",?,?,?
36,BAM70020062,"TRANS MOS NX7002AK(60V,0.19A,0.325W)SMD",IC,1,NXP,NX7002AK,Q11,?,Comp-Approve,End of Design
37,BAM70020068,"TRANS MOS 2N7002A-7(60V,0.115A,0.25W)",IC,2,DDS,2N7002A-7,"Q6,Q8",?,?,?
38,BC000340033,"DIODE SMD SDMK0340L-7-F(40V,30MA)",IC,1,?,?,D17,?,?,?
39,BC0161SS000,"DIODE SMD RB161SS-20T2R(30V,1A)SCHOTTKY",IC,1,ROH,RB161SS-20T2R,D16,?,Comp-Approve,End of Design
40,BC01DBVR000,"DIODE SMD TPD4E001DBVR(5.5V,0.1UA)SOT23",IC,3,TIC,TPD4E001DBVR,"U16,U34,U35",?,?,?
41,BC01DBVR000,"DIODE SMD TPD4E001DBVR(5.5V,0.1UA)SOT23",EMPTY,2,TIC,TPD4E001DBVR,"U8,U9",?,?,?
42,BC0BAS70Z01,"DIODE SMD BAS70-05-7-F(70V,SHTKY,SOT-23)",IC,1,DDS,BAS70-05-7-F,U48,?,Comp-Approve,End of Design
43,BCBAT54CZ04,"DIODE SMD BAT54C(30V,0.2A,SCHOTTKY)",IC,1,PJT,BAT54C,U11,?,Comp-Approve,End of Design
44,BCSS0530Z00,"DIODE SMD SS0530(30V,0.5A)SOD-123",IC,1,PJT,SS0530,D11,?,?,?
45,BCSS0530Z00,"DIODE SMD SS0530(30V,0.5A)SOD-123",EMPTY,1,PJT,SS0530,D9,?,?,?
46,BCZA462AZ01,"DIODE SMD BZA462A(6.2V,100MA,SOT457)",IC,1,PHI,BZA462A,D10,?,?,?
47,BCZA462AZ01,"DIODE SMD BZA462A(6.2V,100MA,SOT457)",EMPTY,1,PHI,BZA462A,D12,?,?,?
48,BEBL0261Z00,LED SMD(2P)BLUE(12-215/BHC-YMNRY/3C),IC,2,?,12-215/BHC-YMNRY/3C,"D14,D15",?,?,?
49,BEGR0278Z00,LED SMD(2P) GREEN(19-213/GVC-AMNB/3T),IC,5,?,19-213/GVC-AMNB/3T,"D0,D1,D2,D3,D8",?,?,?
50,BERD0034Z07,LED SMD(2P) RED (19-217/R6C-P1Q2/3T),IC,4,?,19-217/R6C-P1Q2/3T,"D4,D5,D6,D7",?,?,?
51,BF625000023,"OSC SMD 25MHZ(+-25PPM,3.3V)7X25000018",MISC,2,TXC,7X25000018,"OSC1,OSC2",?,?,?
52,BG625000802,"XTAL SMD 25MHZ(+-20PPM,20PF)7M25020008",MISC,1,TXC,7M25020008,Y1,?,?,?
53,CH0106F0B00,CHIP0402,NPO,5,?,?,"C205,C206,C207,C211,C212",?,?,?
54,CH01206JB05,CAP CHIP 12P 50V(+-5%.C0G.0402),C0G,2,?,?,"C141,C145",?,?,?
55,CH02206JB08,CHIP0402,EMPTY,1,?,?,C152,?,?,?
56,CH0336F0B00,"CAP CHIP 33P 50V(+-1%,C0G,0402)",C0G,3,?,?,"C208,C209,C210",?,?,?
57,CH06806JB01,CAP CHIP 68P 50V(+-5%.COG.0402),COG,1,?,?,PC272,?,?,?
58,CH11006JB00,"CAP CHIP 100P 50V(+-5%,NPO,0402)",NPO,6,?,?,"C9,C165,C166,C167,C275,PC239",?,?,?
59,CH11006JB18,CAP CHIP 100P 50V(+-5%.X7R.0402),EMPTY,2,?,?,"C213,C214",?,Comp-Approve,End of Design
60,CH14706KB18,CHIP0402,X7R,5,?,?,"C172,C178,C179,C324,C326",?,?,?
61,CH22206KB16,"CAP CHIP 2200P 50V(+-10%,X7R,0402)",X7R,1,?,?,C63,?,?,?
62,CH2336K1B12,CHIP0402,X7R,1,?,?,PC273,?,?,?
63,CH2474K1B08,"CAP CHIP 4700P 25V(+-10%,X7R,0402)MUR",EMPTY,1,?,?,C223,?,?,?
64,CH30106KB19,"CAP CHIP 0.001U 50V(10%,X7R,0402)",X7R,6,?,?,"C150,C151,C153,C154,C155,C156",?,Comp-Release Qty,End of Design
65,CH31006KB18,"CAP CHIP 0.01U 50V(+-10%,X7R,0402)",X7R,10,?,?,"C133,C134,C135,C136,C137,C138,C163,C164,C170,C246",?,?,?
66,CH31006KB18,"CAP CHIP 0.01U 50V(+-10%,X7R,0402)",EMPTY,3,?,?,"C21,C142,C169",?,?,?
67,CH4104K1B00,"CAP CHIP 0.1U 25V(+-10%,X7R,0402)",X7R,171,?,?,"C6,C7,C8,C10,C13,C14,C17,C18,C19,C20,C23,C24,C25,C26,C27,C28,C29,C31,C33,C34,C36,C37,C39,C41,C45,C49,C50,C51,C54,C57,C59,C65,C66,C68,C69,C70,C71,C72,C73,C74,C76,C77,C79,C81,C82,C83,C84,C85,C86,C87,C88,C89,C91,C92,C93,C94,C95,C96,C97,C98,C99,C100,C101,C102,C103,C105,C107,C109,C112,C130,C139,C140,C144,C146,C147,C148,C149,C157,C158,C159,C160,C168,C173,C174,C175,C180,C182,C185,C186,C187,C189,C191,C192,C197,C200,C201,C202,C203,C217,C219,C221,C222,C225,C236,C237,C240,C241,C242,C245,C249,C250,C251,C253,C254,C255,C261,C263,C264,C265,C266,C268,C269,C272,C274,C276,C278,C279,C280,C283,C284,C285,C287,C289,C290,C292,C293,C294,C295,C296,C297,C298,C299,C300,C301,C302,C303,C305,C307,C308,C309,C311,C314,C318,C321,C328,C331,C332,C333,C334,PC205,PC210,PC212,PC223,PC225,PC235,PC249,PC253,PC255,PC263,PC266,PC271",?,?,?
68,CH4104K1B00,"CAP CHIP 0.1U 25V(+-10%,X7R,0402)",EMPTY,4,?,?,"C22,C238,C239,C304",?,?,?
69,CH4223K1B00,"CAP CHIP 0.22U 16V(10%,X7R,0402)",X7R,5,?,?,"C12,PC216,PC224,PC254,PC264",?,Comp-Approve,End of Design
70,CH4223K1B00,"CAP CHIP 0.22U 16V(10%,X7R,0402)",EMPTY,1,?,?,C229,?,Comp-Approve,End of Design
71,CH5103K1900,CHIP0603,EMPTY,1,?,?,C204,?,Comp-Approve,End of Design
72,CH5103K9B00,CHIP0402,EMPTY,4,?,?,"C181,C267,C270,C273",?,Comp-Approve,End of Design
73,CH5104KEB02,"CAP CHIP 1UF 25V(+-10%,X6S,0402)",X6S,65,?,?,"C2,C3,C4,C5,C30,C32,C35,C38,C43,C46,C47,C48,C52,C53,C56,C58,C60,C61,C62,C64,C67,C75,C78,C80,C90,C104,C106,C108,C110,C111,C114,C115,C116,C117,C119,C122,C127,C128,C129,C161,C176,C194,C195,C196,C198,C199,C216,C243,C244,C247,C252,C260,C271,C277,C281,C282,C286,C288,C291,PC208,PC221,PC233,PC243,PC250,PC260",?,?,?
74,CH5472K9B00,"CAP CHIP 4.7U 10V(+-10%,X5R,0402)",X5R,5,?,?,"C40,C44,C347,C348,C350",?,?,?
75,CH5474KE906,"CAP CHIP 4.7UF 25V(+-10%,X6S,0603)",X6S,1,?,?,C1,?,?,?
76,CH6101MEB01,"CAP CHIP 10UF 6.3V(+-20%,X6S,0402)",X6S,7,?,?,"C15,C16,C143,C215,C224,C248,C262",?,?,?
77,CH6103ME902,"CAP CHIP 10U 16V(+-20%,X6S,0603)",X6S,6,?,?,"C162,C188,C190,C193,C218,C220",?,?,?
78,CH6104KEA00,"CAP CHIP 10U 25V(+-10%,X6S,0805,H1.25)",X6S,8,?,?,"PC237,PC242,PC248,PC251,PC252,PC261,PC262,PC307",?,?,?
79,CH6221M9B01,"CAP CHIP 22U 6.3V(+-20%,X5R,0402)",X5R,2,?,?,"C346,C349",?,Comp-Approve,End of Design
80,CH6221ME900,"CAP CHIP 22U 6.3V(+-20%,X6S,0603)",X6S,7,?,?,"C42,C55,C118,C121,C123,C124,C126",?,?,?
81,CH6222M9901,"CAP CHIP 22UF 10V(+-20%,X5R,0603)",X5R,7,?,?,"C113,C120,C125,C131,C132,C183,C184",?,?,?
82,CH6222MEA00,"CAP CHIP 22U 10V(+-20%,X6S,0805)",X6S,9,?,?,"C171,PC213,PC214,PC215,PC217,PC226,PC227,PC228,PC229",?,?,?
83,CH6223MEA01,"CAP CHIP 22UF 16V(+-20%,X6S,0805)MUR",X6S,4,?,?,"PC206,PC207,PC218,PC219",?,?,?
84,CH6224M9A00,"CAP CHIP 22U 25V(+-20%,X5R,0805)",X5R,2,?,?,"C329,C330",?,?,?
85,CH622KMEA01,CHIP0805,X6S,8,?,?,"PC256,PC257,PC258,PC259,PC267,PC268,PC269,PC270",?,Comp-Approve,End of Design
86,CH6472M9200,"CAP CHIP 47U 10V(+-20%,X5R,1206)  ",X5R,2,?,?,"C177,C327",?,Comp-Approve,End of Design
87,CS-5102JB02,RES CHIP 5.1 1/16W +-5%(0402)EF,CHIP,2,?,?,"PR539,PR541",?,?,?
88,CS00002JB13,RES CHIP 0 1/16W +-5%(0402)EF,CHIP,149,?,?,"PR193,PR274,R2,R3,R18,R19,R20,R21,R24,R26,R30,R35,R39,R43,R49,R51,R83,R86,R95,R97,R98,R99,R100,R106,R109,R110,R113,R135,R141,R155,R207,R213,R216,R217,R218,R220,R231,R271,R272,R275,R276,R277,R279,R281,R282,R292,R293,R294,R297,R300,R302,R303,R315,R316,R317,R318,R319,R320,R321,R322,R323,R379,R380,R381,R382,R384,R385,R386,R393,R397,R399,R406,R447,R451,R453,R454,R456,R457,R498,R499,R500,R503,R505,R519,R520,R527,R528,R542,R564,R565,R566,R571,R572,R573,R574,R575,R576,R577,R578,R579,R587,R616,R626,R632,R634,R636,R637,R666,R668,R669,R670,R671,R672,R673,R674,R675,R676,R693,R695,R696,R697,R698,R700,R701,R702,R703,R707,R708,R720,R721,R722,R723,R726,R727,R728,R729,R731,R732,R733,R734,R746,R747,R771,R772,R779,R783,R822,R5650,R5660",?,Comp-Approve,End of Design
89,CS00002JB13,RES CHIP 0 1/16W +-5%(0402)EF,EMPTY,28,?,?,"PR205,PR275,R1,R63,R64,R154,R156,R208,R214,R232,R278,R280,R301,R432,R450,R529,R530,R581,R585,R711,R719,R748,R764,R780,R781,R782,R784,R800",?,Comp-Approve,End of Design
90,CS00003J910,RES CHIP 0 1/10W +-5% (0603)EF,EMPTY,3,?,?,"R27,R645,R646",?,Comp-Approve,End of Design
91,CS02202FB02,RES CHIP 22 1/16W +-1%(0402)EF,CHIP,8,?,?,"R286,R288,R538,R539,R628,R629,R630,R631",?,Comp-Approve,End of Design
92,CS02741FE02,RES CHIP 27.4 1/20W +-1%(0201)EF,CHIP,2,?,?,"R402,R403",?,?,?
93,CS03322FB03,RES CHIP 33.2 1/16W +-1%(0402)EF,CHIP,233,?,?,"R28,R29,R33,R36,R37,R46,R47,R52,R53,R54,R60,R65,R71,R84,R85,R90,R93,R102,R104,R111,R112,R114,R119,R120,R121,R123,R128,R129,R130,R131,R132,R133,R137,R138,R139,R142,R143,R144,R146,R147,R148,R150,R151,R152,R153,R157,R158,R159,R160,R162,R165,R166,R168,R170,R171,R172,R173,R174,R175,R176,R177,R178,R179,R180,R181,R182,R183,R184,R185,R186,R187,R198,R199,R200,R201,R215,R221,R222,R223,R224,R225,R236,R237,R242,R243,R263,R270,R394,R404,R405,R407,R408,R409,R410,R420,R421,R423,R424,R425,R426,R427,R433,R434,R435,R436,R437,R439,R440,R442,R443,R444,R445,R448,R449,R458,R459,R460,R461,R462,R463,R465,R466,R468,R469,R470,R471,R472,R473,R474,R475,R476,R477,R479,R480,R481,R482,R483,R484,R485,R486,R489,R494,R501,R509,R510,R511,R512,R513,R514,R515,R516,R517,R518,R522,R524,R525,R526,R531,R533,R534,R535,R536,R537,R540,R541,R545,R546,R547,R548,R549,R550,R551,R553,R554,R561,R562,R567,R570,R580,R582,R583,R584,R589,R590,R594,R635,R638,R639,R643,R644,R690,R691,R704,R705,R713,R715,R718,R724,R725,R750,R757,R759,R760,R761,R762,R763,R766,R767,R769,R773,R799,R801,R802,R803,R804,R807,R812,R813,R824,R825,R826,R833,R836,R837,R840,R841,R852,R859,R860,R861,R862,R863,R864",?,Comp-Approve,End of Design
94,CS03322FB03,RES CHIP 33.2 1/16W +-1%(0402)EF,EMPTY,13,?,?,"R80,R96,R107,R677,R678,R679,R680,R681,R682,R688,R689,R752,R827",?,Comp-Approve,End of Design
95,CS04992FB07,RES CHIP 49.9 1/16W +-1%(0402)EF,CHIP,2,?,?,"R108,R192",?,Comp-Approve,End of Design
96,CS06042FB03,RES CHIP 60.4 1/16W +-1%(0402)EF,CHIP,2,?,?,"R7,R8",?,Comp-Approve,End of Design
97,CS11002FB07,RES CHIP 100 1/16W +-1%(0402)EF,EMPTY,5,?,?,"R125,R417,R743,R744,R745",?,Comp-Approve,End of Design
98,CS11002FB07,RES CHIP 100 1/16W +-1%(0402)EF,CHIP,11,?,?,"R94,R134,R411,R412,R413,R415,R419,R431,R506,R507,R694",?,Comp-Approve,End of Design
99,CS11202FB02,RES CHIP 120 1/16W +-1%(0402)EF,CHIP,48,?,?,"R326,R327,R328,R329,R330,R331,R332,R333,R334,R335,R336,R337,R338,R339,R340,R341,R342,R343,R344,R345,R346,R347,R348,R349,R351,R352,R353,R354,R355,R356,R357,R358,R359,R360,R361,R362,R363,R364,R365,R366,R367,R368,R369,R370,R371,R372,R373,R374",?,Comp-Approve,End of Design
100,CS11202FB02,RES CHIP 120 1/16W +-1%(0402)EF,EMPTY,2,?,?,"R350,R375",?,Comp-Approve,End of Design
101,CS11502FB07,RES CHIP 150 1/16W +-1%(0402)EF,CHIP,6,?,?,"R22,R23,R25,R87,R88,R89",?,Comp-Approve,End of Design
102,CS12202FB04,RES CHIP 220 1/16W +-1%(0402)EF,CHIP,3,?,?,"R304,R305,R306",?,?,?
103,CS12402FB01,RES CHIP 240 1/16W +-1%(0402)EF,CHIP,2,?,?,"R6,R127",?,Comp-Approve,End of Design
104,CS13302FB00,RES CHIP 330 1/16W +-1%(0402)EF,CHIP,1,?,?,R167,?,Comp-Approve,End of Design
105,CS14992FB06,RES CHIP 499 1/16W +-1%(0402)EF,CHIP,1,?,?,R287,?,Comp-Approve,End of Design
106,CS16652FB00,RES CHIP 665 1/16W +-1%(0402)EF,CHIP,1,?,?,R793,?,Comp-Approve,End of Design
107,CS17502FB03,RES CHIP 750 1/16W +-1%(0402)EF,CHIP,8,?,?,"R597,R598,R599,R600,R601,R602,R603,R604",?,Comp-Approve,End of Design
108,CS21002FB06,RES CHIP 1K 1/16W +-1%(0402)EF,CHIP,13,?,?,"R4,R5,R15,R210,R324,R325,R568,R569,R735,R736,R775,R795,R796",?,Comp-Approve,End of Design
109,CS21002FB06,RES CHIP 1K 1/16W +-1%(0402)EF,EMPTY,5,?,?,"R73,R77,R633,R684,R685",?,Comp-Approve,End of Design
110,CS21242FB04,RES CHIP 1.24K 1/16W +-1%(0402)EF,CHIP,1,?,?,R400,?,Comp-Approve,End of Design
111,CS21501FE14,RES CHIP 1.5K 1/20W +-1%(0201)EF,CHIP,2,?,?,"R401,R756",?,?,?
112,CS21502FB07,RES CHIP 1.5K 1/16W +-1%(0402)EF,EMPTY,1,?,?,R283,?,Comp-Approve,End of Design
113,CS21502FB07,RES CHIP 1.5K 1/16W +-1%(0402)EF,CHIP,1,?,?,R285,?,Comp-Approve,End of Design
114,CS21692FB04,RES CHIP 1.69K 1/16W +-1%(0402)EF,CHIP,1,?,?,R791,?,Comp-Approve,End of Design
115,CS22002FB07,RES CHIP 2K 1/16W +-1%(0402)EF,CHIP,16,?,?,"R74,R75,R76,R78,R79,R82,R124,R467,R714,R751,R786,R788,R790,R792,R794,R798",?,Comp-Approve,End of Design
116,CS22002FB07,RES CHIP 2K 1/16W +-1%(0402)EF,EMPTY,1,?,?,R40,?,Comp-Approve,End of Design
117,CS22202JB07,RES CHIP 2.2K 1/16W +-5%(0402)EF,CHIP,2,?,?,"R91,R92",?,Comp-Approve,End of Design
118,CS22212FB06,RES CHIP 2.21K 1/16W +-1%(0402)EF,EMPTY,2,?,?,"R16,R17",?,Comp-Approve,End of Design
119,CS22742FB05,RES CHIP 2.74K 1/16W +-1%(0402)EF,CHIP,1,?,?,R235,?,Comp-Approve,End of Design
120,CS22872FB03,RES CHIP 2.87K 1/16W +-1%(0402)EF,CHIP,2,?,?,"R789,R797",?,Comp-Approve,End of Design
121,CS24702FB06,RES CHIP 4.7K 1/16W +-1%(0402)EF,CHIP,129,?,?,"R9,R31,R32,R38,R44,R45,R55,R56,R57,R58,R61,R62,R67,R68,R69,R70,R72,R81,R101,R103,R115,R116,R117,R140,R145,R149,R161,R163,R169,R188,R189,R190,R191,R194,R195,R196,R197,R212,R238,R239,R240,R241,R244,R245,R246,R247,R248,R249,R250,R251,R252,R253,R254,R255,R256,R257,R258,R259,R260,R261,R262,R264,R265,R268,R269,R291,R298,R299,R307,R309,R311,R376,R387,R389,R416,R422,R428,R429,R430,R438,R446,R452,R488,R490,R492,R521,R563,R586,R588,R591,R592,R606,R607,R608,R609,R610,R611,R612,R613,R615,R617,R621,R622,R624,R625,R627,R667,R683,R692,R706,R717,R730,R738,R739,R740,R741,R749,R758,R765,R774,R805,R806,R816,R835,R842,R843,R844,R848,R851",?,Comp-Approve,End of Design
122,CS24702FB06,RES CHIP 4.7K 1/16W +-1%(0402)EF,EMPTY,39,?,?,"R12,R13,R14,R34,R229,R266,R267,R284,R308,R310,R312,R388,R390,R414,R418,R455,R487,R491,R496,R593,R595,R596,R605,R623,R640,R641,R686,R687,R699,R737,R742,R753,R754,R770,R821,R828,R845,R846,R870",?,Comp-Approve,End of Design
123,CS25362FB02,RES CHIP 5.36K 1/16W +-1%(0402)EF,CHIP,1,?,?,R787,?,Comp-Approve,End of Design
124,CS25492FB02,RES CHIP 5.49K 1/16W +-1%(0402) EF,CHIP,1,?,?,PR276,?,Comp-Approve,End of Design
125,CS28202JB05,RES CHIP 8.2K 1/16W +-5% (0402) EF,CHIP,4,?,?,"R504,R619,R768,R839",?,Comp-Approve,End of Design
126,CS31002FB08,RES CHIP 10K 1/16W +-1%(0402)EF,CHIP,35,?,?,"PR241,PR242,PR244,PR255,PR498,PR500,R10,R42,R50,R59,R126,R136,R203,R204,R209,R211,R226,R227,R230,R289,R383,R464,R497,R508,R523,R618,R709,R716,R808,R809,R810,R811,R814,R815,R866",?,Comp-Approve,End of Design
127,CS31002FB08,RES CHIP 10K 1/16W +-1%(0402)EF,EMPTY,9,?,?,"R41,R105,R202,R228,R295,R377,R398,R712,R834",?,Comp-Approve,End of Design
128,CS31202FB04,RES CHIP 12K 1/16W +-1%(0402)EF,CHIP,2,?,?,"R830,R832",?,Comp-Approve,End of Design
129,CS31242FB02,RES CHIP 12.4K 1/16W +-1%(0402)EF,CHIP,2,?,?,"PR526,PR530",?,Comp-Approve,End of Design
130,CS31502FB05,RES CHIP 15K 1/16W +-1%(0402)EF,CHIP,1,?,?,R831,?,Comp-Approve,End of Design
131,CS31582FB02,RES CHIP 15.8K 1/16W +-1% (0402)EF,CHIP,1,?,?,R785,?,Comp-Approve,End of Design
132,CS32002FB06,RES CHIP 20K 1/16W +-1%(0402)EF,CHIP,2,?,?,"R205,R378",?,Comp-Approve,End of Design
133,CS32052FB02,RES CHIP 20.5K 1/16W +-1%(0402)EF,CHIP,1,?,?,PR525,?,Comp-Approve,End of Design
134,CS32552FB06,RES CHIP 25.5K 1/16W +-1%(0402)EF,CHIP,1,?,?,R829,?,Comp-Approve,End of Design
135,CS34702FB01,RES CHIP 47K 1/16W +-1%(0402)EF,CHIP,2,?,?,"R290,R776",?,Comp-Approve,End of Design
136,CS34992FB05,RES CHIP 49.9K 1/16W +-1%(0402)EF,CHIP,2,?,?,"R233,R234",?,Comp-Approve,End of Design
137,CS35602FB00,RES CHIP 56K 1/16W +-1%(0402)EF,CHIP,1,?,?,PR534,?,?,?
138,CS36042FB04,RES CHIP 60.4K 1/16W +-1%(0402)EF,CHIP,1,?,?,PR532,?,Comp-Approve,End of Design
139,CS39102FB06,RES CHIP 91K 1/16W +-1%(0402)EF,CHIP,1,?,?,PR527,?,?,?
140,CS41002BB08,RES CHIP 100K 1/16W +-0.1%(0402)EF,CHIP,1,?,?,PR543,?,?,?
141,CS41002FB09,RES CHIP 100K 1/16W +-1%(0402)EF,EMPTY,9,?,?,"PR245,R206,R219,R274,R296,R817,R818,R819,R820",?,Comp-Approve,End of Design
142,CS41002FB09,RES CHIP 100K 1/16W +-1%(0402)EF,CHIP,18,?,?,"PR522,R66,R118,R122,R193,R273,R314,R391,R392,R478,R502,R614,R620,R642,R710,R755,R778,R823",?,Comp-Approve,End of Design
143,CS41502FB04,RES CHIP 150K 1/16W +-1%(0402)EF,CHIP,1,?,?,PR496,?,Comp-Approve,End of Design
144,CS41502FB04,RES CHIP 150K 1/16W +-1%(0402)EF,EMPTY,1,?,?,R493,?,Comp-Approve,End of Design
145,CS42002FB05,RES CHIP 200K 1/16W +-1%(0402)EF,CHIP,1,?,?,R777,?,Comp-Approve,End of Design
146,CS44702FB02,RES CHIP 470K 1/16W +-1%(0402)EF,CHIP,1,?,?,R313,?,Comp-Approve,End of Design
147,CS46812FB06,RES CHIP 681K 1/16W +-1%(0402)EF,CHIP,1,?,?,PR521,?,?,?
148,CS51002FB05,RES CHIP 1M 1/16W +-1%(0402)EF,CHIP,2,?,?,"R395,R396",?,Comp-Approve,End of Design
149,CS51002FB05,RES CHIP 1M 1/16W +-1%(0402)EF,EMPTY,1,?,?,R441,?,Comp-Approve,End of Design
150,CV-10B0MZ13,IND SMD 1UH 20%11A(PCMC063T-1R0MN),IND,2,?,?,"PL31,PL33",?,?,?
151,CV-3360MZ07,"IND SMD 3.3UH,6A20%(PCMC063T-3R3MN)",IND,1,?,?,PL35,?,?,?
152,CV-47A0MZ10,IND SMD 4.7UH +-20% 10A(PCMB104E-4R7MS),IND,1,?,?,PL34,?,?,?
153,CX21SN67000,"EMI FILTER DLW21SN670HQ2L(67,320MA)",EMPTY,3,MUR,DLW21SN670HQ2L,"L21,L22,L23",?,?,?
154,CX21SN67000,"EMI FILTER DLW21SN670HQ2L(67,320MA)",IND,1,MUR,DLW21SN670HQ2L,L24,?,?,?
155,CX220TN1001,"EMI FILTER BLM18SN220TN1D(22,8000MA)",IND,4,?,?,"PL4,PL19,PL29,PL32",?,?,?
156,CX221T15000,"EMI FILTER HCB1608KF-221T15(220,1500MA)",IND,1,?,?,L20,?,?,?
157,CX5PX121001,"EMI FILTER BLM15PX121SN1D(120,2A)",IND,5,?,?,"L18,L31,L32,L33,L34",?,?,?
158,CX8BA470003,EMI FITTER BLM18BA470SN1(47.300MA),IND,3,?,?,"L28,L29,L30",?,Comp-Approve,End of Design
159,CX8EG121000,EMI FILTER BLM18EG121SN1D(120.2A),IND,4,?,?,"L17,L19,L26,L27",?,?,?
160,CX8PG121009,"EMI FILTER BLM18PG121SN(120,2000MA)",IND,14,?,?,"L3,L4,L5,L6,L7,L8,L9,L10,L11,L12,L13,L14,L15,L16",?,?,?
161,CX8PG121009,"EMI FILTER BLM18PG121SN(120,2000MA)",EMPTY,1,?,?,L2,?,?,?
162,DFHD03MS251,"CONN SMD HEADER 3P 1R MS(P2.54, H9.3)",EMPTY,1,PRX,212-91-035BR2,J6,?,?,?
163,DFHD07MS260,"CONN DIP HEADER 7P 1R MS(P2, H6.05)",IO,1,TYC,2-2355933-7,J7,?,?,?
164,DFHD13MR071,"CONN SMD HEADER 13P 1R MR(P1,H2.9)",IO,1,ACS,50224-0130C-001,J8,?,?,?
165,DFHS05FR105,"CONN SMD MICRO USB 5P 1R FR(P0.65,H2.66)",IO,1,SIT,2UB2141-000111F,J4,?,?,?
166,DFHS09FR401,"CONN DIP USB3.0 9P 2R FR(P2.0,H7.74)",IO,1,APL,GSB311131HR,J2,?,?,?
167,DFHS11FS009,"CONN SMD HOUSING 11P 2R FS(P1,H3.28)",IO,2,BER,91920-31111LF,"J5,J10",?,?,?
168,DFHS20FR233,"CONN SMD HOUSING 20P 4R FR(P0.6,H5.9)",IO,1,FOX,3VM11207-D730-7H,J3,?,?,?
169,DFHS75FR133,"CONN SMD HOUSING 75P 2R FR(P0.5,H6.7)",IO,1,LTK,NASA0-S6730-TS67,J31,?,?,?
170,DFTJ14FR046,CONN SMD RJ45+TRANS 14P FR(H10.1)W/LED,IO,1,UDE,RS6-QU-0001,J1,?,?,?
171,DG016000006,"IC SOCKET SMD 16P(SPI,SOIC)(P1.27,H5.8)",IO,1,LTS,ACA-SPI-006-P06,J40,?,?,?
172,DHP00002F00,SWITCH SMD PUSH BUTTON DHNF-02F-T-V-T/R,MECH,3,DIP,DHNF-02F-T-V-T/R,"SW1,SW2,SW3",?,?,?
173,DHPTA34W200,SWITCH TACT(TA3-4W2-Q-T/R),MECH,2,DIP,TA3-4W2-Q-T/R,"SW6,SW7",?,?,?
174,DK050TPU011,"FUSE SMD 0.5A,6V(POLY,1206L050YR)",IC,1,?,?,L1,?,?,?
175,DK110TPU003,FUSE SMD 1.1A 8V POLY(SMD1206P110TFT),IC,1,?,?,FS1,?,?,?
176,DUMMY1,QUANTA_LOGO_7X26,EMPTY,1,?,?,DM19,?,?,?
177,DUMMY2,WEEE,EMPTY,1,?,?,DM4,?,?,?
178,DUMMY3,PB-E1_SMALL,EMPTY,1,?,?,DM7,?,?,?
179,DUMMY50,HOLE_TOOLINGD125N_T2-0,EMPTY,2,?,?,"H2B1,H2B2",?,?,?
180,DUMMY8,BMC_FLASH,MECH,2,?,?,"DM2,DM5",?,?,?
181,GOLD195,GOLD_168P_ME1016810106011,EMPTY,1,APL,?,GF1,?,?,?
182,HOLE1101,HOLE_C5-5D3-2B7_NPB,EMPTY,2,?,?,"H6,H7",?,?,?
183,HOLE1211,HOLE_C6-03D3-13B6-03_NPB,EMPTY,2,?,?,"H5,H9",?,?,?
184,HOLE620,HOLE_C6D3-4B6_NPB,EMPTY,2,?,?,"H1,H2",?,?,?
185,N_A,"(USE SYM_2)TDR 3PIN,2X141MIL 1X100MIL P2P",EMPTY,6,?,?,"DB1,DB2,DB3,DB4,DB5,DB6",?,?,?
186,N_A,DIFF_TEST_PAD DIP FOR FTS ONLY,EMPTY,16,?,?,"X1,X2,X5,X6,X7,X8,X11,X12,X13,X14,X17,X18,X19,X20,X23,X24",?,?,?
187,TMP_QAL009555K04,IC(24P) PCA9555PW(TSSOP)EP,IC,1,?,?,U40,?,?,?
188,TP24,Probe for DELTA-L measurement,EMPTY,16,?,?,"J9,J11,J12,J16,J17,J19,J20,J22,J23,J24,J25,J26,J27,J28,J29,J30",?,?,?
TOTAL, , , ,1407, , , , , , 
